(kicad_pcb
	(version 20260206)
	(generator "pcbnew")
	(generator_version "10.0")
	(general
		(thickness 1.6)
		(legacy_teardrops no)
	)
	(paper "A4")
	(title_block
		(title "peb — Lightning_PEB_BRD.brd")
		(comment 1 "Lightning (Wiwynn / Facebook NVMe JBOF) / footprints 225-232 of 2563")
	)
	(layers
		(0 "F.Cu" signal "TOP")
		(4 "In1.Cu" signal "L2GND")
		(6 "In2.Cu" signal "L3")
		(8 "In3.Cu" signal "L4VCC")
		(10 "In4.Cu" signal "L5VCC")
		(12 "In5.Cu" signal "L6")
		(14 "In6.Cu" signal "L7GND")
		(2 "B.Cu" signal "BOTTOM")
		(9 "F.Adhes" user "F.Adhesive")
		(11 "B.Adhes" user "B.Adhesive")
		(13 "F.Paste" user "Package Geometry/Pastemask Top")
		(15 "B.Paste" user "Package Geometry/Pastemask Bottom")
		(5 "F.SilkS" user "Ref Des/Silkscreen Top")
		(7 "B.SilkS" user "Ref Des/Silkscreen Bottom")
		(1 "F.Mask" user "Board Geometry/Soldermask Top")
		(3 "B.Mask" user "Board Geometry/Soldermask Bottom")
		(17 "Dwgs.User" user "User.Drawings")
		(19 "Cmts.User" user "User.Comments")
		(21 "Eco1.User" user "User.Eco1")
		(23 "Eco2.User" user "User.Eco2")
		(25 "Edge.Cuts" user "Board Geometry/Outline")
		(27 "Margin" user)
		(31 "F.CrtYd" user "Package Geometry/Place Bound Top")
		(29 "B.CrtYd" user "Package Geometry/Place Bound Bottom")
		(35 "F.Fab" user "Ref Des/Assembly Top")
		(33 "B.Fab" user "Ref Des/Assembly Bottom")
	)
	(footprint ""
		(layer "F.Cu")
		(at 145.1356 -41.402 180)
		(property "Reference" "R768"
			(at 0 0 180)
			(layer "F.SilkS")
			(hide yes)
			(effects
				(font
					(size 1.27 1.27)
				)
			)
		)
		(property "Value" "4K7R2F-GP"
			(at 0.064008 -3.993896 180)
			(unlocked yes)
			(layer "F.Fab")
			(hide yes)
			(effects
				(font
					(size 1.016 1.016)
					(thickness 0.1524)
				)
			)
		)
		(property "Device Type" "R402H16"
			(at 0.064008 -5.517896 180)
			(unlocked yes)
			(layer "F.Fab")
			(hide yes)
			(effects
				(font
					(size 1.016 1.016)
					(thickness 0.1524)
				)
			)
		)
		(duplicate_pad_numbers_are_jumpers no)
		(fp_line
			(start 0.508 -0.9398)
			(end -0.508 -0.9398)
			(stroke
				(width 0.1524)
				(type default)
			)
			(layer "F.SilkS")
		)
		(fp_line
			(start -0.508 -0.9398)
			(end -0.508 0.9398)
			(stroke
				(width 0.1524)
				(type default)
			)
			(layer "F.SilkS")
		)
		(fp_rect
			(start -0.508 0.9398)
			(end 0.508 -0.9398)
			(stroke
				(width 0)
				(type default)
			)
			(fill no)
			(layer "F.CrtYd")
		)
		(fp_rect
			(start -0.508 0.9398)
			(end 0.508 -0.9398)
			(stroke
				(width 0)
				(type default)
			)
			(fill no)
			(layer "F.Fab")
		)
		(pad "1" smd custom
			(at 0 -0.4445 180)
			(size 0.1397 0.1397)
			(layers "F.Cu" "F.Mask" "F.Paste")
			(net "DUT_VDDO")
			(options
				(clearance outline)
				(anchor circle)
			)
			(primitives
				(gr_poly
					(pts
						(arc
							(start -0.1778 -0.2794)
							(mid -0.249642 -0.249642)
							(end -0.2794 -0.1778)
						)
						(arc
							(start -0.2794 0.1778)
							(mid -0.249642 0.249642)
							(end -0.1778 0.2794)
						)
						(arc
							(start 0.1778 0.2794)
							(mid 0.249642 0.249642)
							(end 0.2794 0.1778)
						)
						(arc
							(start 0.2794 -0.1778)
							(mid 0.249642 -0.249642)
							(end 0.1778 -0.2794)
						)
					)
					(width 0)
					(fill yes)
				)
			)
		)
		(pad "2" smd custom
			(at 0 0.4445 180)
			(size 0.1397 0.1397)
			(layers "F.Cu" "F.Mask" "F.Paste")
			(net "EJTAG_RSTB")
			(options
				(clearance outline)
				(anchor circle)
			)
			(primitives
				(gr_poly
					(pts
						(arc
							(start -0.1778 -0.2794)
							(mid -0.249642 -0.249642)
							(end -0.2794 -0.1778)
						)
						(arc
							(start -0.2794 0.1778)
							(mid -0.249642 0.249642)
							(end -0.1778 0.2794)
						)
						(arc
							(start 0.1778 0.2794)
							(mid 0.249642 0.249642)
							(end 0.2794 0.1778)
						)
						(arc
							(start 0.2794 -0.1778)
							(mid 0.249642 -0.249642)
							(end 0.1778 -0.2794)
						)
					)
					(width 0)
					(fill yes)
				)
			)
		)
	)
	(footprint ""
		(layer "F.Cu")
		(at 226.925124 -190.601092)
		(property "Reference" "R7972"
			(at 0 0 0)
			(layer "F.SilkS")
			(hide yes)
			(effects
				(font
					(size 1.27 1.27)
				)
			)
		)
		(property "Value" "0R2J-2-GP"
			(at 0.064008 -3.993896 0)
			(unlocked yes)
			(layer "F.Fab")
			(hide yes)
			(effects
				(font
					(size 1.016 1.016)
					(thickness 0.1524)
				)
			)
		)
		(property "Device Type" "R402H16"
			(at 0.064008 -5.517896 0)
			(unlocked yes)
			(layer "F.Fab")
			(hide yes)
			(effects
				(font
					(size 1.016 1.016)
					(thickness 0.1524)
				)
			)
		)
		(duplicate_pad_numbers_are_jumpers no)
		(fp_line
			(start -0.508 -0.9398)
			(end -0.508 0.9398)
			(stroke
				(width 0.1524)
				(type default)
			)
			(layer "F.SilkS")
		)
		(fp_line
			(start 0.508 -0.9398)
			(end -0.508 -0.9398)
			(stroke
				(width 0.1524)
				(type default)
			)
			(layer "F.SilkS")
		)
		(fp_rect
			(start -0.508 0.9398)
			(end 0.508 -0.9398)
			(stroke
				(width 0)
				(type default)
			)
			(fill no)
			(layer "F.CrtYd")
		)
		(fp_rect
			(start -0.508 0.9398)
			(end 0.508 -0.9398)
			(stroke
				(width 0)
				(type default)
			)
			(fill no)
			(layer "F.Fab")
		)
		(pad "1" smd custom
			(at 0 -0.4445)
			(size 0.1397 0.1397)
			(layers "F.Cu" "F.Mask" "F.Paste")
			(net "SSD_PERST#8")
			(options
				(clearance outline)
				(anchor circle)
			)
			(primitives
				(gr_poly
					(pts
						(arc
							(start -0.1778 -0.2794)
							(mid -0.249642 -0.249642)
							(end -0.2794 -0.1778)
						)
						(arc
							(start -0.2794 0.1778)
							(mid -0.249642 0.249642)
							(end -0.1778 0.2794)
						)
						(arc
							(start 0.1778 0.2794)
							(mid 0.249642 0.249642)
							(end 0.2794 0.1778)
						)
						(arc
							(start 0.2794 -0.1778)
							(mid 0.249642 -0.249642)
							(end 0.1778 -0.2794)
						)
					)
					(width 0)
					(fill yes)
				)
			)
		)
		(pad "2" smd custom
			(at 0 0.4445)
			(size 0.1397 0.1397)
			(layers "F.Cu" "F.Mask" "F.Paste")
			(net "SSD_PERST#8_R")
			(options
				(clearance outline)
				(anchor circle)
			)
			(primitives
				(gr_poly
					(pts
						(arc
							(start -0.1778 -0.2794)
							(mid -0.249642 -0.249642)
							(end -0.2794 -0.1778)
						)
						(arc
							(start -0.2794 0.1778)
							(mid -0.249642 0.249642)
							(end -0.1778 0.2794)
						)
						(arc
							(start 0.1778 0.2794)
							(mid 0.249642 0.249642)
							(end 0.2794 0.1778)
						)
						(arc
							(start 0.2794 -0.1778)
							(mid 0.249642 -0.249642)
							(end 0.1778 -0.2794)
						)
					)
					(width 0)
					(fill yes)
				)
			)
		)
	)
	(footprint ""
		(layer "F.Cu")
		(at 79.502 -56.3626 -90)
		(property "Reference" "R961"
			(at 0 0 270)
			(layer "F.SilkS")
			(hide yes)
			(effects
				(font
					(size 1.27 1.27)
				)
			)
		)
		(property "Value" "300R2F-GP"
			(at 0.064008 -3.993896 270)
			(unlocked yes)
			(layer "F.Fab")
			(hide yes)
			(effects
				(font
					(size 1.016 1.016)
					(thickness 0.1524)
				)
			)
		)
		(property "Device Type" "R402H16"
			(at 0.064008 -5.517896 270)
			(unlocked yes)
			(layer "F.Fab")
			(hide yes)
			(effects
				(font
					(size 1.016 1.016)
					(thickness 0.1524)
				)
			)
		)
		(duplicate_pad_numbers_are_jumpers no)
		(fp_line
			(start -0.508 -0.9398)
			(end -0.508 0.9398)
			(stroke
				(width 0.1524)
				(type default)
			)
			(layer "F.SilkS")
		)
		(fp_line
			(start 0.508 -0.9398)
			(end -0.508 -0.9398)
			(stroke
				(width 0.1524)
				(type default)
			)
			(layer "F.SilkS")
		)
		(fp_rect
			(start -0.508 0.9398)
			(end 0.508 -0.9398)
			(stroke
				(width 0)
				(type default)
			)
			(fill no)
			(layer "F.CrtYd")
		)
		(fp_rect
			(start -0.508 0.9398)
			(end 0.508 -0.9398)
			(stroke
				(width 0)
				(type default)
			)
			(fill no)
			(layer "F.Fab")
		)
		(pad "1" smd custom
			(at 0 -0.4445 270)
			(size 0.1397 0.1397)
			(layers "F.Cu" "F.Mask" "F.Paste")
			(net "BMC_CPU_DIS")
			(options
				(clearance outline)
				(anchor circle)
			)
			(primitives
				(gr_poly
					(pts
						(arc
							(start -0.1778 -0.2794)
							(mid -0.249642 -0.249642)
							(end -0.2794 -0.1778)
						)
						(arc
							(start -0.2794 0.1778)
							(mid -0.249642 0.249642)
							(end -0.1778 0.2794)
						)
						(arc
							(start 0.1778 0.2794)
							(mid 0.249642 0.249642)
							(end 0.2794 0.1778)
						)
						(arc
							(start 0.2794 -0.1778)
							(mid 0.249642 -0.249642)
							(end 0.1778 -0.2794)
						)
					)
					(width 0)
					(fill yes)
				)
			)
		)
		(pad "2" smd custom
			(at 0 0.4445 270)
			(size 0.1397 0.1397)
			(layers "F.Cu" "F.Mask" "F.Paste")
			(net "GND")
			(options
				(clearance outline)
				(anchor circle)
			)
			(primitives
				(gr_poly
					(pts
						(arc
							(start -0.1778 -0.2794)
							(mid -0.249642 -0.249642)
							(end -0.2794 -0.1778)
						)
						(arc
							(start -0.2794 0.1778)
							(mid -0.249642 0.249642)
							(end -0.1778 0.2794)
						)
						(arc
							(start 0.1778 0.2794)
							(mid 0.249642 0.249642)
							(end 0.2794 0.1778)
						)
						(arc
							(start 0.2794 -0.1778)
							(mid 0.249642 -0.249642)
							(end 0.1778 -0.2794)
						)
					)
					(width 0)
					(fill yes)
				)
			)
		)
	)
	(footprint ""
		(layer "F.Cu")
		(at 18.415 -107.315 180)
		(property "Reference" "PR70"
			(at 0 0 180)
			(layer "F.SilkS")
			(hide yes)
			(effects
				(font
					(size 1.27 1.27)
				)
			)
		)
		(property "Value" "4K75R2F-1-GP"
			(at 0.064008 -3.993896 180)
			(unlocked yes)
			(layer "F.Fab")
			(hide yes)
			(effects
				(font
					(size 1.016 1.016)
					(thickness 0.1524)
				)
			)
		)
		(property "Device Type" "R402H16"
			(at 0.064008 -5.517896 180)
			(unlocked yes)
			(layer "F.Fab")
			(hide yes)
			(effects
				(font
					(size 1.016 1.016)
					(thickness 0.1524)
				)
			)
		)
		(duplicate_pad_numbers_are_jumpers no)
		(fp_line
			(start 0.508 -0.9398)
			(end -0.508 -0.9398)
			(stroke
				(width 0.1524)
				(type default)
			)
			(layer "F.SilkS")
		)
		(fp_line
			(start -0.508 -0.9398)
			(end -0.508 0.9398)
			(stroke
				(width 0.1524)
				(type default)
			)
			(layer "F.SilkS")
		)
		(fp_rect
			(start -0.508 0.9398)
			(end 0.508 -0.9398)
			(stroke
				(width 0)
				(type default)
			)
			(fill no)
			(layer "F.CrtYd")
		)
		(fp_rect
			(start -0.508 0.9398)
			(end 0.508 -0.9398)
			(stroke
				(width 0)
				(type default)
			)
			(fill no)
			(layer "F.Fab")
		)
		(pad "1" smd custom
			(at 0 -0.4445 180)
			(size 0.1397 0.1397)
			(layers "F.Cu" "F.Mask" "F.Paste")
			(net "VR_P1V26_STBY_FB")
			(options
				(clearance outline)
				(anchor circle)
			)
			(primitives
				(gr_poly
					(pts
						(arc
							(start -0.1778 -0.2794)
							(mid -0.249642 -0.249642)
							(end -0.2794 -0.1778)
						)
						(arc
							(start -0.2794 0.1778)
							(mid -0.249642 0.249642)
							(end -0.1778 0.2794)
						)
						(arc
							(start 0.1778 0.2794)
							(mid 0.249642 0.249642)
							(end 0.2794 0.1778)
						)
						(arc
							(start 0.2794 -0.1778)
							(mid 0.249642 -0.249642)
							(end 0.1778 -0.2794)
						)
					)
					(width 0)
					(fill yes)
				)
			)
		)
		(pad "2" smd custom
			(at 0 0.4445 180)
			(size 0.1397 0.1397)
			(layers "F.Cu" "F.Mask" "F.Paste")
			(net "GND")
			(options
				(clearance outline)
				(anchor circle)
			)
			(primitives
				(gr_poly
					(pts
						(arc
							(start -0.1778 -0.2794)
							(mid -0.249642 -0.249642)
							(end -0.2794 -0.1778)
						)
						(arc
							(start -0.2794 0.1778)
							(mid -0.249642 0.249642)
							(end -0.1778 0.2794)
						)
						(arc
							(start 0.1778 0.2794)
							(mid 0.249642 0.249642)
							(end 0.2794 0.1778)
						)
						(arc
							(start 0.2794 -0.1778)
							(mid 0.249642 -0.249642)
							(end 0.1778 -0.2794)
						)
					)
					(width 0)
					(fill yes)
				)
			)
		)
	)
	(footprint ""
		(layer "F.Cu")
		(at 53.721 -140.843 -90)
		(property "Reference" "SR944"
			(at 0 0 270)
			(layer "F.SilkS")
			(hide yes)
			(effects
				(font
					(size 1.27 1.27)
				)
			)
		)
		(property "Value" "4K75R2F-1-GP"
			(at 0.064008 -3.993896 270)
			(unlocked yes)
			(layer "F.Fab")
			(hide yes)
			(effects
				(font
					(size 1.016 1.016)
					(thickness 0.1524)
				)
			)
		)
		(property "Device Type" "R402H16"
			(at 0.064008 -5.517896 270)
			(unlocked yes)
			(layer "F.Fab")
			(hide yes)
			(effects
				(font
					(size 1.016 1.016)
					(thickness 0.1524)
				)
			)
		)
		(duplicate_pad_numbers_are_jumpers no)
		(fp_line
			(start -0.508 -0.9398)
			(end -0.508 0.9398)
			(stroke
				(width 0.1524)
				(type default)
			)
			(layer "F.SilkS")
		)
		(fp_line
			(start 0.508 -0.9398)
			(end -0.508 -0.9398)
			(stroke
				(width 0.1524)
				(type default)
			)
			(layer "F.SilkS")
		)
		(fp_rect
			(start -0.508 0.9398)
			(end 0.508 -0.9398)
			(stroke
				(width 0)
				(type default)
			)
			(fill no)
			(layer "F.CrtYd")
		)
		(fp_rect
			(start -0.508 0.9398)
			(end 0.508 -0.9398)
			(stroke
				(width 0)
				(type default)
			)
			(fill no)
			(layer "F.Fab")
		)
		(pad "1" smd custom
			(at 0 -0.4445 270)
			(size 0.1397 0.1397)
			(layers "F.Cu" "F.Mask" "F.Paste")
			(net "P3V3_STBY")
			(options
				(clearance outline)
				(anchor circle)
			)
			(primitives
				(gr_poly
					(pts
						(arc
							(start -0.1778 -0.2794)
							(mid -0.249642 -0.249642)
							(end -0.2794 -0.1778)
						)
						(arc
							(start -0.2794 0.1778)
							(mid -0.249642 0.249642)
							(end -0.1778 0.2794)
						)
						(arc
							(start 0.1778 0.2794)
							(mid 0.249642 0.249642)
							(end 0.2794 0.1778)
						)
						(arc
							(start 0.2794 -0.1778)
							(mid 0.249642 -0.249642)
							(end 0.1778 -0.2794)
						)
					)
					(width 0)
					(fill yes)
				)
			)
		)
		(pad "2" smd custom
			(at 0 0.4445 270)
			(size 0.1397 0.1397)
			(layers "F.Cu" "F.Mask" "F.Paste")
			(net "BMC_FW_DET_BOARD_VER_0")
			(options
				(clearance outline)
				(anchor circle)
			)
			(primitives
				(gr_poly
					(pts
						(arc
							(start -0.1778 -0.2794)
							(mid -0.249642 -0.249642)
							(end -0.2794 -0.1778)
						)
						(arc
							(start -0.2794 0.1778)
							(mid -0.249642 0.249642)
							(end -0.1778 0.2794)
						)
						(arc
							(start 0.1778 0.2794)
							(mid 0.249642 0.249642)
							(end 0.2794 0.1778)
						)
						(arc
							(start 0.2794 -0.1778)
							(mid 0.249642 -0.249642)
							(end 0.1778 -0.2794)
						)
					)
					(width 0)
					(fill yes)
				)
			)
		)
	)
	(footprint ""
		(layer "F.Cu")
		(at 80.6196 -137.795 -90)
		(property "Reference" "R5772"
			(at 0 0 270)
			(layer "F.SilkS")
			(hide yes)
			(effects
				(font
					(size 1.27 1.27)
				)
			)
		)
		(property "Value" "1KR2F-3-GP"
			(at 0.064008 -3.993896 270)
			(unlocked yes)
			(layer "F.Fab")
			(hide yes)
			(effects
				(font
					(size 1.016 1.016)
					(thickness 0.1524)
				)
			)
		)
		(property "Device Type" "R402H16"
			(at 0.064008 -5.517896 270)
			(unlocked yes)
			(layer "F.Fab")
			(hide yes)
			(effects
				(font
					(size 1.016 1.016)
					(thickness 0.1524)
				)
			)
		)
		(duplicate_pad_numbers_are_jumpers no)
		(fp_line
			(start -0.508 -0.9398)
			(end -0.508 0.9398)
			(stroke
				(width 0.1524)
				(type default)
			)
			(layer "F.SilkS")
		)
		(fp_line
			(start 0.508 -0.9398)
			(end -0.508 -0.9398)
			(stroke
				(width 0.1524)
				(type default)
			)
			(layer "F.SilkS")
		)
		(fp_rect
			(start -0.508 0.9398)
			(end 0.508 -0.9398)
			(stroke
				(width 0)
				(type default)
			)
			(fill no)
			(layer "F.CrtYd")
		)
		(fp_rect
			(start -0.508 0.9398)
			(end 0.508 -0.9398)
			(stroke
				(width 0)
				(type default)
			)
			(fill no)
			(layer "F.Fab")
		)
		(pad "1" smd custom
			(at 0 -0.4445 270)
			(size 0.1397 0.1397)
			(layers "F.Cu" "F.Mask" "F.Paste")
			(net "P1V26_STBY")
			(options
				(clearance outline)
				(anchor circle)
			)
			(primitives
				(gr_poly
					(pts
						(arc
							(start -0.1778 -0.2794)
							(mid -0.249642 -0.249642)
							(end -0.2794 -0.1778)
						)
						(arc
							(start -0.2794 0.1778)
							(mid -0.249642 0.249642)
							(end -0.1778 0.2794)
						)
						(arc
							(start 0.1778 0.2794)
							(mid 0.249642 0.249642)
							(end 0.2794 0.1778)
						)
						(arc
							(start 0.2794 -0.1778)
							(mid 0.249642 -0.249642)
							(end 0.1778 -0.2794)
						)
					)
					(width 0)
					(fill yes)
				)
			)
		)
		(pad "2" smd custom
			(at 0 0.4445 270)
			(size 0.1397 0.1397)
			(layers "F.Cu" "F.Mask" "F.Paste")
			(net "ADC_P1V26")
			(options
				(clearance outline)
				(anchor circle)
			)
			(primitives
				(gr_poly
					(pts
						(arc
							(start -0.1778 -0.2794)
							(mid -0.249642 -0.249642)
							(end -0.2794 -0.1778)
						)
						(arc
							(start -0.2794 0.1778)
							(mid -0.249642 0.249642)
							(end -0.1778 0.2794)
						)
						(arc
							(start 0.1778 0.2794)
							(mid 0.249642 0.249642)
							(end 0.2794 0.1778)
						)
						(arc
							(start 0.2794 -0.1778)
							(mid 0.249642 -0.249642)
							(end 0.1778 -0.2794)
						)
					)
					(width 0)
					(fill yes)
				)
			)
		)
	)
	(footprint ""
		(layer "F.Cu")
		(at 45.339 -146.399504)
		(property "Reference" "TP237"
			(at 0 0 0)
			(layer "F.SilkS")
			(hide yes)
			(effects
				(font
					(size 1.27 1.27)
				)
			)
		)
		(property "Value" "TPAD28-2-GP"
			(at -0.0127 -1.6637 0)
			(unlocked yes)
			(layer "F.Fab")
			(hide yes)
			(effects
				(font
					(size 1.016 1.016)
					(thickness 0.1524)
				)
			)
		)
		(property "Device Type" "TPAD28"
			(at -0.0127 -3.1877 0)
			(unlocked yes)
			(layer "F.Fab")
			(hide yes)
			(effects
				(font
					(size 1.016 1.016)
					(thickness 0.1524)
				)
			)
		)
		(duplicate_pad_numbers_are_jumpers no)
		(fp_poly
			(pts
				(arc
					(start 0.3556 0)
					(mid -0.3556 0)
					(end 0.3556 0)
				)
			)
			(stroke
				(width 0)
				(type default)
			)
			(fill no)
			(layer "F.CrtYd")
		)
		(fp_poly
			(pts
				(arc
					(start 0.6096 0)
					(mid -0.6096 0)
					(end 0.6096 0)
				)
			)
			(stroke
				(width 0)
				(type default)
			)
			(fill no)
			(layer "F.Fab")
		)
		(pad "1" smd circle
			(at 0 0)
			(size 0.7112 0.7112)
			(layers "F.Cu" "F.Mask" "F.Paste")
			(net "TP_GPIOO6")
		)
	)
	(footprint ""
		(layer "F.Cu")
		(at 192.8368 -27.7622 -90)
		(property "Reference" "C143"
			(at 0 0 270)
			(layer "F.SilkS")
			(hide yes)
			(effects
				(font
					(size 1.27 1.27)
				)
			)
		)
		(property "Value" "SCD1U10V2KX-5GP"
			(at 1.1811 -2.7051 270)
			(unlocked yes)
			(layer "F.Fab")
			(hide yes)
			(effects
				(font
					(size 1.016 1.016)
					(thickness 0.1524)
				)
			)
		)
		(property "Device Type" "C402H22"
			(at 1.1811 -4.2291 270)
			(unlocked yes)
			(layer "F.Fab")
			(hide yes)
			(effects
				(font
					(size 1.016 1.016)
					(thickness 0.1524)
				)
			)
		)
		(duplicate_pad_numbers_are_jumpers no)
		(fp_rect
			(start -0.4318 0.9525)
			(end 0.4318 -0.9525)
			(stroke
				(width 0)
				(type default)
			)
			(fill no)
			(layer "F.CrtYd")
		)
		(fp_rect
			(start -0.4318 0.9525)
			(end 0.4318 -0.9525)
			(stroke
				(width 0)
				(type default)
			)
			(fill no)
			(layer "F.Fab")
		)
		(pad "1" smd custom
			(at 0 -0.4445 270)
			(size 0.1524 0.1524)
			(layers "F.Cu" "F.Mask" "F.Paste")
			(net "P3V3_STBY")
			(options
				(clearance outline)
				(anchor circle)
			)
			(primitives
				(gr_poly
					(pts
						(arc
							(start 0.3048 -0.2032)
							(mid 0.275042 -0.275042)
							(end 0.2032 -0.3048)
						)
						(arc
							(start -0.2032 -0.3048)
							(mid -0.275042 -0.275042)
							(end -0.3048 -0.2032)
						)
						(arc
							(start -0.3048 0.2032)
							(mid -0.275042 0.275042)
							(end -0.2032 0.3048)
						)
						(arc
							(start 0.2032 0.3048)
							(mid 0.275042 0.275042)
							(end 0.3048 0.2032)
						)
					)
					(width 0)
					(fill yes)
				)
			)
		)
		(pad "2" smd custom
			(at 0 0.4445 270)
			(size 0.1524 0.1524)
			(layers "F.Cu" "F.Mask" "F.Paste")
			(net "GND")
			(options
				(clearance outline)
				(anchor circle)
			)
			(primitives
				(gr_poly
					(pts
						(arc
							(start 0.3048 -0.2032)
							(mid 0.275042 -0.275042)
							(end 0.2032 -0.3048)
						)
						(arc
							(start -0.2032 -0.3048)
							(mid -0.275042 -0.275042)
							(end -0.3048 -0.2032)
						)
						(arc
							(start -0.3048 0.2032)
							(mid -0.275042 0.275042)
							(end -0.2032 0.3048)
						)
						(arc
							(start 0.2032 0.3048)
							(mid 0.275042 0.275042)
							(end 0.3048 0.2032)
						)
					)
					(width 0)
					(fill yes)
				)
			)
		)
	)
)
